FILE_TYPE = CONNECTIVITY;
{Allegro Design Entry HDL 17.2-2016 S081 (4005846) 1/11/2022}
"PAGE_NUMBER" = 303;
0"NC";
1"AGND_HSC\g";
2"P3V3_AUX\g";
3"AGND_HSC\g";
4"AGND_HSC\g";
5"P12V_PSU\g";
6"AGND_HSC\g";
7"HSC_VDD\g";
8"AGND_HSC\g";
9"AGND_HSC\g";
10"HSC_VDD\g";
11"P12V_AUX\g";
12"AGND_HSC\g";
13"AGND_HSC\g";
14"AGND_HSC\g";
15"AGND_HSC\g";
16"P12V_AUX\g";
17"AGND_HSC\g";
18"AGND_HSC\g";
19"AGND_HSC\g";
20"AGND_HSC\g";
21"HSC_VDD\g";
22"GND\g";
23"GND\g";
24"GND\g";
25"GND\g";
26"GND\g";
27"GND\g";
28"SMB_SML1_PMBUS_HSC_SDA";
29"SMB_SML1_PMBUS_HSC_SCL";
30"IRQ_SML1_PMBUS_ALERT_N";
31"IRQ_SML1_PMBUS_ALERT";
32"HSC_EN";
33"HSC_ON";
34"HSC_VIN_UVW_N";
35"SMB_SML1_PMBUS_HSC_R_SDA";
36"HSC_EN_R";
37"HSC_SS";
38"HSC_ADDR";
39"HSC_VDD18";
40"HSC_ON_R";
41"SMB_SML1_PMBUS_HSC_L_SCL";
42"HSC_IMON";
43"HSC_CS";
44"HSC_VTEMP";
45"HSC_MODE";
46"HSC_D_OC_R";
47"HSC_FAULT";
48"MB0_P12V_STBY_PWRGD";
49"HSC_D_OC";
50"HSC_VOSEN";
51"HSC_FLT_TYPE";
52"HSC_VSENSE";
53"HSC_VDD_R";
54"IRQ_HSC_FAULT_N";
55"HSC_OCREF";
56"PDB_PRSNT_N";
57"HSC_SCREF";
58"HSC_EN";
59"P12V_PSU_FUSE";
%"UNIVERSAL_GND"
"1","(-17225,175)","0","logical_power","I1";
;
HDL_POWER"GND"
CDS_LIB"logical_power";
"A"23;
%"Q_RES"
"2","(-16575,950)","0","pure_quanta","I10";
;
PART_NUMBER"CS36342FB04"
PACK_TYPE"0402LF"
VALUE"63.4K"
TOLERANCE"1%"
WATTAGE"1/16W"
LOCATION"R3923"
MATERIAL"CHIP"
CDS_LIB"pure_quanta"
$SEC"1"
CDS_SEC"1";
"A"
$PN"1"59;
"B"
$PN"2"56;
%"GND"
"1","(-16800,1600)","0","logical_power","I11";
;
HDL_POWER"GND"
CDS_LIB"logical_power"
SIZE"1B";
"A<SIZE-1..0>\NAC"26;
%"CONN3_210HP1030BR1"
"1","(-16550,1800)","0","pure_quanta","I12";
;
PART_NUMBER"DFHD03MS213"
MATERIAL"IO"
PART_TYPE"THLF"
VALUE"CONN3_210-HP1-030BR1"
LOCATION"JP4003"
CDS_LIB"pure_quanta"
CDS_LMAN_SYM_OUTLINE"-50,100,50,-100"
NEEDS_NO_SIZE"TRUE"
$SEC"1"
CDS_SEC"1";
"1"
$PN"1"0;
"2"
$PN"2"56;
"3"
$PN"3"26;
%"Q_CAP"
"1","(-17150,4325)","0","pure_quanta","I14";
;
PART_NUMBER"CH5104KEB02"
MATERIAL"X6S"
PACK_TYPE"C0402"
ROOM"HSC1_BOM1"
VOLTAGE"25V"
VALUE"1UF"
LOCATION"PC2186"
TOLERANCE"10%"
CDS_LIB"pure_quanta"
$SEC"1"
CDS_SEC"1";
"B"
$PN"2"1;
"A"
$PN"1"53;
%"Q_RES"
"1","(-16350,3200)","0","pure_quanta","I17";
;
PART_NUMBER"CS00002JB13"
WATTAGE"1/16W"
VALUE"0"
TOLERANCE"5%"
PACK_TYPE"0402LF"
MATERIAL"CHIP"
$LOCATION"R3924"
CDS_LIB"pure_quanta"
CDS_LOCATION"R3924"
$SEC"1"
CDS_SEC"1";
"B"
$PN"2"31;
"A"
$PN"1"30;
%"UNIVERSAL_GND"
"1","(-16650,4050)","0","logical_power","I22";
;
HDL_POWER"AGND_HSC"
CDS_LIB"logical_power";
"A"1;
%"Q_CAP"
"1","(-16650,4300)","0","pure_quanta","I23";
;
PART_NUMBER"CH5104KEB02"
VALUE"1UF"
PACK_TYPE"C0402"
MATERIAL"X6S"
VOLTAGE"25V"
ROOM"HSC1_BOM1"
LOCATION"PC2187"
CDS_LIB"pure_quanta"
TOLERANCE"10%"
$SEC"1"
CDS_SEC"1";
"B"
$PN"2"1;
"A"
$PN"1"53;
%"Q_RES"
"1","(-16950,4750)","1","pure_quanta","I24";
;
PART_NUMBER"CS00002JB13"
ROOM"HSC1_BOM1"
MATERIAL"CHIP"
TOLERANCE"5%"
VALUE"0"
PACK_TYPE"0402LF"
WATTAGE"1/16W"
LOCATION"PR2149"
CDS_LIB"pure_quanta"
$SEC"1"
CDS_SEC"1";
"B"
$PN"2"7;
"A"
$PN"1"53;
%"Q_RES"
"1","(-15400,1350)","0","pure_quanta","I26";
;
PART_NUMBER"CS38202FB01"
PACK_TYPE"0402LF"
TOLERANCE"1%"
VALUE"82K"
MATERIAL"CHIP"
WATTAGE"1/16W"
LOCATION"R4901"
CDS_LIB"pure_quanta"
$SEC"1"
CDS_SEC"1";
"B"
$PN"2"58;
"A"
$PN"1"59;
%"UNIVERSAL_GND"
"1","(-15050,2575)","0","logical_power","I28";
;
HDL_POWER"AGND_HSC"
CDS_LIB"logical_power";
"A"18;
%"Q_CAP"
"1","(-14475,850)","0","pure_quanta","I29";
;
PART_NUMBER"CH4106K1B01"
VALUE"100NF"
TOLERANCE"10%"
MATERIAL"X7R"
PACK_TYPE"C0402"
VOLTAGE"50V"
LOCATION"C2179"
CDS_LIB"pure_quanta"
$SEC"1"
CDS_SEC"1";
"B"
$PN"2"6;
"A"
$PN"1"58;
%"Q_CAP"
"1","(-17225,400)","0","pure_quanta","I3";
;
PART_NUMBER"CH4104K1B00"
TOLERANCE"10%"
MATERIAL"X7R"
PACK_TYPE"0402"
VOLTAGE"25V"
VALUE"0.1UF"
LOCATION"C1797"
CDS_LIB"pure_quanta"
$SEC"1"
CDS_SEC"1";
"B"
$PN"2"23;
"A"
$PN"1"56;
%"UNIVERSAL_GND"
"1","(-14575,2250)","0","logical_power","I31";
;
HDL_POWER"AGND_HSC"
CDS_LIB"logical_power";
"A"20;
%"Q_RES"
"1","(-14575,2450)","1","pure_quanta","I32";
;
PART_NUMBER"CS00002JB13"
ROOM"HSC1_BOM1"
TOLERANCE"5%"
PACK_TYPE"0402LF"
VALUE"0"
MATERIAL"CHIP"
WATTAGE"1/16W"
LOCATION"PR3930"
CDS_LIB"pure_quanta"
$SEC"1"
CDS_SEC"1";
"B"
$PN"2"38;
"A"
$PN"1"20;
%"Q_RES"
"1","(-15950,3375)","1","pure_quanta","I33";
;
PART_NUMBER"CS21002FB06"
VALUE"1K"
TOLERANCE"1%"
WATTAGE"1/16W"
PACK_TYPE"0402LF"
MATERIAL"CHIP"
$LOCATION"R3925"
CDS_LIB"pure_quanta"
CDS_LOCATION"R3925"
$SEC"1"
CDS_SEC"1";
"B"
$PN"2"2;
"A"
$PN"1"31;
%"UNIVERSAL_POWER"
"1","(-15950,3550)","0","logical_power","I34";
;
HDL_POWER"P3V3_AUX"
CDS_LIB"logical_power";
"A"2;
%"Q_CAP"
"1","(-15050,2875)","0","pure_quanta","I35";
;
PART_NUMBER"CH5104KEB02"
ROOM"HSC1_BOM1"
VOLTAGE"25V"
MATERIAL"X6S"
VALUE"1UF"
PACK_TYPE"C0402"
$LOCATION"PC2103"
TOLERANCE"10%"
CDS_LIB"pure_quanta"
CDS_LOCATION"PC2103"
$SEC"1"
CDS_SEC"1";
"B"
$PN"2"18;
"A"
$PN"1"39;
%"UNIVERSAL_POWER"
"1","(-15325,3550)","0","logical_power","I36";
;
HDL_POWER"HSC_VDD"
BOM_COST"MIO_VRD_SB"
CDS_LIB"logical_power";
"A"21;
%"Q_RES"
"1","(-15400,3775)","0","pure_quanta","I37";
;
PART_NUMBER"CS00002JB13"
TOLERANCE"5%"
PACK_TYPE"0402LF"
MATERIAL"CHIP"
ROOM"HSC1_BOM1"
VALUE"0"
WATTAGE"1/16W"
LOCATION"R1714"
CDS_LIB"pure_quanta"
$SEC"1"
CDS_SEC"1";
"B"
$PN"2"35;
"A"
$PN"1"28;
%"Q_RES"
"1","(-15400,3875)","0","pure_quanta","I38";
;
PART_NUMBER"CS03322FB03"
ROOM"HSC1_BOM1"
PACK_TYPE"0402LF"
WATTAGE"1/16W"
VALUE"33.2"
TOLERANCE"1%"
MATERIAL"CHIP"
LOCATION"R3909"
CDS_LIB"pure_quanta"
$SEC"1"
CDS_SEC"1";
"B"
$PN"2"41;
"A"
$PN"1"29;
%"UNIVERSAL_GND"
"1","(-15425,4275)","0","logical_power","I39";
;
HDL_POWER"AGND_HSC"
CDS_LIB"logical_power";
"A"4;
%"Q_RES"
"2","(-16525,450)","0","pure_quanta","I4";
;
PART_NUMBER"CS33302FB00"
WATTAGE"1/16W"
PACK_TYPE"0402LF"
VALUE"33K"
TOLERANCE"1%"
LOCATION"R3907"
CDS_LIB"pure_quanta"
MATERIAL"CHIP"
$SEC"1"
CDS_SEC"1";
"A"
$PN"1"56;
"B"
$PN"2"24;
%"Q_RES"
"2","(-15425,4600)","0","pure_quanta","I40";
;
PART_NUMBER"CS24992BB04"
TOLERANCE"0.1%"
PACK_TYPE"0402LF"
ROOM"HSC1_BOM1"
MATERIAL"CHIP"
WATTAGE"1/16W"
VALUE"4.99K"
LOCATION"PR3927"
CDS_LIB"pure_quanta"
$SEC"1"
CDS_SEC"1";
"A"
$PN"1"52;
"B"
$PN"2"4;
%"Q_RES"
"1","(-14825,3225)","0","pure_quanta","I41";
;
PART_NUMBER"CS00002JB13"
PACK_TYPE"0402LF"
TOLERANCE"5%"
VALUE"0"
ROOM"HSC1_BOM1"
MATERIAL"CHIP"
WATTAGE"1/16W"
LOCATION"PR3928"
CDS_LIB"pure_quanta"
$SEC"1"
CDS_SEC"1";
"B"
$PN"2"40;
"A"
$PN"1"33;
%"Q_RES"
"1","(-14575,2850)","1","pure_quanta","I42";
;
PART_NUMBER"CS21002FB06"
PACK_TYPE"0402LF"
TOLERANCE"1%"
VALUE"1K"
WATTAGE"1/16W"
MATERIAL"EMPTY"
LOCATION"PR3929"
CDS_LIB"pure_quanta"
$SEC"1"
CDS_SEC"1";
"B"
$PN"2"39;
"A"
$PN"1"38;
%"Q_RES"
"1","(-14825,3475)","0","pure_quanta","I43";
;
PART_NUMBER"CS31002FB08"
WATTAGE"1/16W"
VALUE"10K"
TOLERANCE"1%"
PACK_TYPE"0402LF"
ROOM"HSC1_BOM1"
MATERIAL"CHIP"
$LOCATION"PR2106"
CDS_LIB"pure_quanta"
CDS_LOCATION"PR2106"
$SEC"1"
CDS_SEC"1";
"B"
$PN"2"34;
"A"
$PN"1"21;
%"Q_RES"
"1","(-14825,3350)","0","pure_quanta","I44";
;
PART_NUMBER"CS00002JB13"
TOLERANCE"5%"
VALUE"0"
ROOM"HSC1_BOM1"
PACK_TYPE"0402LF"
MATERIAL"CHIP"
WATTAGE"1/16W"
LOCATION"R2586"
CDS_LIB"pure_quanta"
$SEC"1"
CDS_SEC"1";
"B"
$PN"2"36;
"A"
$PN"1"32;
%"Q_CAP"
"1","(-14900,4600)","0","pure_quanta","I45";
;
PART_NUMBER"CH31006KB18"
VOLTAGE"50V"
MATERIAL"X7R"
PACK_TYPE"C0402"
ROOM"HSC1_BOM1"
VALUE"0.01UF"
LOCATION"PC2189"
TOLERANCE"10%"
CDS_LIB"pure_quanta"
$SEC"1"
CDS_SEC"1";
"B"
$PN"2"4;
"A"
$PN"1"52;
%"UNIVERSAL_POWER"
"1","(-16950,4975)","0","logical_power","I47";
;
HDL_POWER"HSC_VDD"
CDS_LIB"logical_power"
BOM_COST"MIO_VRD_SB";
"A"7;
%"MOSFET_NCH_GDS_ESD_PROTECTED"
"1","(-16025,625)","0","pure_quanta","I5";
;
PART_NUMBER"BAM70020002"
VALUE"2N7002K"
PART_TYPE"SMLF"
MATERIAL"IC"
$LOCATION"U290"
CDS_LMAN_SYM_OUTLINE"-125,150,125,-150"
CDS_LIB"pure_quanta"
NEEDS_NO_SIZE"TRUE"
CDS_LOCATION"U290"
$SEC"1"
CDS_SEC"1";
"S"
$PN"S"24;
"G"
$PN"G"56;
"D"
$PN"D"58;
%"UNIVERSAL_POWER"
"1","(-15950,5650)","0","logical_power","I50";
;
HDL_POWER"P12V_PSU"
BOM_COST"MIO_VRD_SB"
CDS_LIB"logical_power";
"A"5;
%"Q_CAP"
"1","(-15950,5050)","0","pure_quanta","I51";
;
PART_NUMBER"CH5104KEB02"
PACK_TYPE"C0402"
MATERIAL"X6S"
ROOM"HSC1_BOM1"
VALUE"1UF"
VOLTAGE"25V"
LOCATION"PC2188"
TOLERANCE"10%"
CDS_LIB"pure_quanta"
$SEC"1"
CDS_SEC"1";
"B"
$PN"2"22;
"A"
$PN"1"5;
%"Q_RES"
"2","(-15425,5050)","0","pure_quanta","I52";
;
PART_NUMBER"CS37502BB01"
ROOM"HSC1_BOM1"
TOLERANCE"0.1%"
WATTAGE"1/16W"
VALUE"75K"
PACK_TYPE"0402LF"
MATERIAL"CHIP"
LOCATION"PR3926"
CDS_LIB"pure_quanta"
$SEC"1"
CDS_SEC"1";
"A"
$PN"1"5;
"B"
$PN"2"52;
%"GND"
"1","(-13500,1475)","0","logical_power","I53";
;
HDL_POWER"GND"
CDS_LIB"logical_power"
SIZE"1B";
"A<SIZE-1..0>\NAC"27;
%"Q_RES"
"1","(-13175,1725)","0","pure_quanta","I54";
;
PART_NUMBER"CS00002JB13"
PACK_TYPE"0402LF"
TOLERANCE"5%"
WATTAGE"1/16W"
MATERIAL"CHIP"
VALUE"0"
LOCATION"PR3002"
CDS_LIB"pure_quanta"
$SEC"1"
CDS_SEC"1";
"B"
$PN"2"8;
"A"
$PN"1"27;
%"UNIVERSAL_GND"
"1","(-13800,2625)","0","logical_power","I55";
;
HDL_POWER"AGND_HSC"
CDS_LIB"logical_power";
"A"19;
%"MP5990GMA1111Z"
"1","(-13125,3750)","0","pure_quanta","I56";
;
PART_NUMBER"AL005990A03"
ROOM"HSC1_BOM1"
PART_TYPE"SMLF"
VALUE"MP5990GMA-1111-Z"
MATERIAL"IC"
LOCATION"PU289"
CDS_LIB"pure_quanta"
NEEDS_NO_SIZE"TRUE"
CDS_LMAN_SYM_OUTLINE"-425,1125,425,-1125"
$SEC"1"
CDS_SEC"1";
"ADDR"
$PN"23"38;
"VDD18"
$PN"19"39;
"VDD33_2"
$PN"45"53;
"VDD33_1"
$PN"17"53;
"VINSEN"
$PN"9"52;
"VIN10"
$PN"43"5;
"FLT_TYPE"
$PN"40"51;
"GND2"
$PN"44"19;
"VIN1"
$PN"1"5;
"VOUT4"
$PN"30"11;
"VOSEN"
$PN"24"50;
"VOUT10"
$PN"36"11;
"VIN9"
$PN"42"5;
"CS"
$PN"20"43;
"IMON"
$PN"21"42;
"VOUT6"
$PN"32"11;
"SS"
$PN"16"37;
"SCREF_OCWREF"
$PN"25"57;
"OCREF"
$PN"22"55;
"VTEMP"
$PN"15"44;
"VIN6"
$PN"6"5;
"VIN5"
$PN"5"5;
"ON"
$PN"38"40;
"VOUT8"
$PN"34"11;
"PG||OCW#"
$PN"13"48;
"VIN8"
$PN"8"5;
"MODE"
$PN"41"45;
"VOUT7"
$PN"33"11;
"VIN7"
$PN"7"5;
"GOK"
$PN"39"47;
"ALT# \B"
$PN"10"31;
"VOUT9"
$PN"35"11;
"VOUT5"
$PN"31"11;
"D_OC"
$PN"37"46;
"SCL"
$PN"11"41;
"VIN_UVW# \B"
$PN"14"34;
"SDA"
$PN"12"35;
"GND1"
$PN"18"19;
"VIN4"
$PN"4"5;
"VIN3"
$PN"3"5;
"EN"
$PN"26"36;
"VIN2"
$PN"2"5;
"VOUT1"
$PN"27"11;
"VOUT2"
$PN"28"11;
"VOUT3"
$PN"29"11;
%"UNIVERSAL_GND"
"1","(-12725,1525)","0","logical_power","I57";
;
HDL_POWER"AGND_HSC"
CDS_LIB"logical_power";
"A"8;
%"Q_RES"
"1","(-11875,3675)","0","pure_quanta","I58";
;
PART_NUMBER"CS22002BB07"
PACK_TYPE"0402LF"
WATTAGE"1/16W"
ROOM"HSC1_BOM1"
TOLERANCE"0.1%"
VALUE"2K"
MATERIAL"CHIP"
$LOCATION"PR1131"
CDS_LIB"pure_quanta"
CDS_LOCATION"PR1131"
$SEC"1"
CDS_SEC"1";
"B"
$PN"2"3;
"A"
$PN"1"43;
%"Q_RES"
"2","(-11975,4675)","0","pure_quanta","I59";
;
PART_NUMBER"CS24992BB04"
VALUE"4.99K"
TOLERANCE"0.1%"
ROOM"HSC1_BOM1"
WATTAGE"1/16W"
MATERIAL"CHIP"
PACK_TYPE"0402LF"
LOCATION"PR3932"
CDS_LIB"pure_quanta"
$SEC"1"
CDS_SEC"1";
"A"
$PN"1"50;
"B"
$PN"2"17;
%"GND"
"1","(-16000,175)","0","logical_power","I6";
;
HDL_POWER"GND"
CDS_LIB"logical_power"
SIZE"1B";
"A<SIZE-1..0>\NAC"24;
%"UNIVERSAL_GND"
"1","(-11700,1950)","0","logical_power","I60";
;
HDL_POWER"AGND_HSC"
CDS_LIB"logical_power";
"A"15;
%"Q_RES"
"2","(-11700,2150)","0","pure_quanta","I61";
;
PART_NUMBER"CS26192FB03"
WATTAGE"1/16W"
TOLERANCE"1%"
ROOM"HSC1_BOM1"
PACK_TYPE"0402LF"
MATERIAL"CHIP"
VALUE"6.19K"
LOCATION"R1117"
CDS_LIB"pure_quanta"
$SEC"1"
CDS_SEC"1";
"A"
$PN"1"48;
"B"
$PN"2"15;
%"Q_RES"
"2","(-11700,2600)","0","pure_quanta","I62";
;
PART_NUMBER"CS31692FB03"
ROOM"HSC1_BOM1"
WATTAGE"1/16W"
MATERIAL"CHIP"
PACK_TYPE"0402LF"
TOLERANCE"1%"
VALUE"16.9K"
LOCATION"R3933"
CDS_LIB"pure_quanta"
$SEC"1"
CDS_SEC"1";
"A"
$PN"1"16;
"B"
$PN"2"48;
%"UNIVERSAL_GND"
"1","(-11225,2700)","0","logical_power","I64";
;
HDL_POWER"AGND_HSC"
CDS_LIB"logical_power";
"A"14;
%"UNIVERSAL_POWER"
"1","(-11700,2800)","0","logical_power","I68";
;
HDL_POWER"P12V_AUX"
BOM_COST"MIO_VRD_SB"
CDS_LIB"logical_power";
"A"16;
%"Q_CAP"
"1","(-11225,2875)","0","pure_quanta","I69";
;
PART_NUMBER"CH3683K1B09"
ROOM"HSC1_BOM1"
PACK_TYPE"0402"
VALUE"0.068UF"
MATERIAL"X7R"
VOLTAGE"16V"
LOCATION"PC2191"
CDS_LIB"pure_quanta"
TOLERANCE"10%"
$SEC"1"
CDS_SEC"1";
"B"
$PN"2"14;
"A"
$PN"1"37;
%"Q_RES"
"2","(-15100,750)","0","pure_quanta","I7";
;
PART_NUMBER"CS33162FB02"
VALUE"31.6K"
WATTAGE"1/16W"
MATERIAL"CHIP"
PACK_TYPE"0402LF"
TOLERANCE"1%"
LOCATION"R2585"
CDS_LIB"pure_quanta"
$SEC"1"
CDS_SEC"1";
"A"
$PN"1"58;
"B"
$PN"2"25;
%"UNIVERSAL_GND"
"1","(-11350,3575)","0","logical_power","I71";
;
HDL_POWER"AGND_HSC"
CDS_LIB"logical_power";
"A"3;
%"UNIVERSAL_GND"
"1","(-11500,4375)","0","logical_power","I74";
;
HDL_POWER"AGND_HSC"
CDS_LIB"logical_power";
"A"17;
%"Q_CAP"
"1","(-11500,4675)","0","pure_quanta","I75";
;
PART_NUMBER"CH31006KB18"
VOLTAGE"50V"
PACK_TYPE"C0402"
MATERIAL"X7R"
ROOM"HSC1_BOM1"
VALUE"0.01UF"
LOCATION"PC2190"
TOLERANCE"10%"
CDS_LIB"pure_quanta"
$SEC"1"
CDS_SEC"1";
"B"
$PN"2"17;
"A"
$PN"1"50;
%"Q_CAP"
"1","(-10650,3125)","0","pure_quanta","I77";
;
PART_NUMBER"CH30106KB19"
VOLTAGE"50V"
MATERIAL"X7R"
ROOM"HSC1_BOM1"
PACK_TYPE"C0402"
VALUE"0.001UF"
LOCATION"PC2192"
CDS_LIB"pure_quanta"
TOLERANCE"10%"
$SEC"1"
CDS_SEC"1";
"B"
$PN"2"9;
"A"
$PN"1"44;
%"UNIVERSAL_GND"
"1","(-10350,2800)","0","logical_power","I78";
;
HDL_POWER"AGND_HSC"
CDS_LIB"logical_power";
"A"9;
%"Q_RES"
"2","(-10175,3150)","0","pure_quanta","I79";
;
PART_NUMBER"CS31002FB08"
PACK_TYPE"0402LF"
WATTAGE"1/16W"
ROOM"HSC1_BOM1"
MATERIAL"CHIP"
VALUE"10K"
TOLERANCE"1%"
LOCATION"PR3935"
CDS_LIB"pure_quanta"
$SEC"1"
CDS_SEC"1";
"A"
$PN"1"44;
"B"
$PN"2"9;
%"GND"
"1","(-15100,500)","0","logical_power","I8";
;
HDL_POWER"GND"
CDS_LIB"logical_power"
SIZE"1B";
"A<SIZE-1..0>\NAC"25;
%"Q_RES"
"1","(-10675,4275)","0","pure_quanta","I81";
;
PART_NUMBER"CS02202FB02"
VALUE"22"
ROOM"HSC1_BOM1"
MATERIAL"CHIP"
PACK_TYPE"0402LF"
WATTAGE"1/16W"
TOLERANCE"1%"
LOCATION"R2588"
CDS_LIB"pure_quanta"
$SEC"1"
CDS_SEC"1";
"B"
$PN"2"54;
"A"
$PN"1"47;
%"Q_RES"
"1","(-10675,4100)","0","pure_quanta","I82";
;
PART_NUMBER"CS02202FB02"
WATTAGE"1/16W"
PACK_TYPE"0402LF"
ROOM"HSC1_BOM1"
MATERIAL"CHIP"
TOLERANCE"1%"
VALUE"22"
LOCATION"R3934"
CDS_LIB"pure_quanta"
$SEC"1"
CDS_SEC"1";
"B"
$PN"2"49;
"A"
$PN"1"46;
%"Q_RES"
"1","(-9850,3975)","0","pure_quanta","I84";
;
PART_NUMBER"CS41202FB05"
ROOM"HSC1_BOM1"
MATERIAL"CHIP"
TOLERANCE"1%"
PACK_TYPE"0402LF"
WATTAGE"1/16W"
VALUE"120K"
LOCATION"PR3937"
CDS_LIB"pure_quanta"
$SEC"1"
CDS_SEC"1";
"B"
$PN"2"13;
"A"
$PN"1"45;
%"Q_RES"
"2","(-10150,4600)","0","pure_quanta","I85";
;
PART_NUMBER"CS24702FB06"
ROOM"HSC1_BOM1"
PACK_TYPE"0402LF"
WATTAGE"1/16W"
TOLERANCE"1%"
VALUE"4.7K"
MATERIAL"CHIP"
LOCATION"R3936"
CDS_LIB"pure_quanta"
$SEC"1"
CDS_SEC"1";
"A"
$PN"1"10;
"B"
$PN"2"49;
%"Q_RES"
"2","(-12050,5125)","0","pure_quanta","I86";
;
PART_NUMBER"CS37502BB01"
PACK_TYPE"0402LF"
ROOM"HSC1_BOM1"
VALUE"75K"
WATTAGE"1/16W"
MATERIAL"CHIP"
TOLERANCE"0.1%"
LOCATION"PR3931"
CDS_LIB"pure_quanta"
$SEC"1"
CDS_SEC"1";
"A"
$PN"1"11;
"B"
$PN"2"50;
%"UNIVERSAL_POWER"
"1","(-9950,4950)","0","logical_power","I87";
;
HDL_POWER"HSC_VDD"
BOM_COST"MIO_VRD_SB"
CDS_LIB"logical_power";
"A"10;
%"UNIVERSAL_POWER"
"1","(-10300,5500)","0","logical_power","I88";
;
HDL_POWER"P12V_AUX"
CDS_LIB"logical_power"
BOM_COST"MIO_VRD_SB";
"A"11;
%"Q_CAP"
"1","(-9825,3550)","0","pure_quanta","I89";
;
PART_NUMBER"CH3474K1B04"
ROOM"HSC1_BOM1"
MATERIAL"X7R"
VOLTAGE"25V"
VALUE"0.047UF"
PACK_TYPE"C0402"
LOCATION"PC2193"
TOLERANCE"10%"
CDS_LIB"pure_quanta"
$SEC"1"
CDS_SEC"1";
"B"
$PN"2"12;
"A"
$PN"1"42;
%"UNIVERSAL_GND"
"1","(-14475,500)","0","logical_power","I9";
;
HDL_POWER"AGND_HSC"
CDS_LIB"logical_power";
"A"6;
%"UNIVERSAL_GND"
"1","(-9350,3300)","0","logical_power","I90";
;
HDL_POWER"AGND_HSC"
CDS_LIB"logical_power";
"A"12;
%"Q_RES"
"2","(-9350,3575)","0","pure_quanta","I91";
;
PART_NUMBER"CS22002BB07"
ROOM"HSC1_BOM1"
MATERIAL"CHIP"
WATTAGE"1/16W"
TOLERANCE"0.1%"
VALUE"2K"
PACK_TYPE"0402LF"
$LOCATION"PR1133"
CDS_LIB"pure_quanta"
CDS_LOCATION"PR1133"
$SEC"1"
CDS_SEC"1";
"A"
$PN"1"42;
"B"
$PN"2"12;
%"Q_RES"
"2","(-9725,4600)","0","pure_quanta","I93";
;
PART_NUMBER"CS24702FB06"
ROOM"HSC1_BOM1"
WATTAGE"1/16W"
MATERIAL"CHIP"
TOLERANCE"1%"
PACK_TYPE"0402LF"
VALUE"4.7K"
LOCATION"R2587"
CDS_LIB"pure_quanta"
$SEC"1"
CDS_SEC"1";
"A"
$PN"1"10;
"B"
$PN"2"54;
%"UNIVERSAL_GND"
"1","(-9275,3900)","0","logical_power","I94";
;
HDL_POWER"AGND_HSC"
CDS_LIB"logical_power";
"A"13;
%"GND"
"1","(-15950,4775)","0","logical_power","I97";
;
SIZE"1B"
HDL_POWER"GND"
CDS_LIB"logical_power";
"A<SIZE-1..0>\NAC"22;
END.
